(kicad_pcb
	(version 20260206)
	(generator "pcbnew")
	(generator_version "10.0")
	(general
		(thickness 1.6)
		(legacy_teardrops no)
	)
	(paper "A4")
	(title_block
		(title "Wiwynn_Tioga_Pass_MB.brd")
		(comment 1 "Tioga Pass / footprints 2713-2716 of 4770")
	)
	(layers
		(0 "F.Cu" signal "TOP")
		(4 "In1.Cu" signal "L2GND")
		(6 "In2.Cu" signal "L3")
		(8 "In3.Cu" signal "L4GND")
		(10 "In4.Cu" signal "L5")
		(12 "In5.Cu" signal "L6GND")
		(14 "In6.Cu" signal "L7VCC")
		(16 "In7.Cu" signal "L8VCC")
		(18 "In8.Cu" signal "L9GND")
		(20 "In9.Cu" signal "L10")
		(22 "In10.Cu" signal "L11GND")
		(24 "In11.Cu" signal "L12")
		(26 "In12.Cu" signal "L13GND")
		(2 "B.Cu" signal "BOTTOM")
		(9 "F.Adhes" user "F.Adhesive")
		(11 "B.Adhes" user "B.Adhesive")
		(13 "F.Paste" user "Package Geometry/Pastemask Top")
		(15 "B.Paste" user "Package Geometry/Pastemask Bottom")
		(5 "F.SilkS" user "Ref Des/Silkscreen Top")
		(7 "B.SilkS" user "Ref Des/Silkscreen Bottom")
		(1 "F.Mask" user "Board Geometry/Soldermask Top")
		(3 "B.Mask" user "Board Geometry/Soldermask Bottom")
		(17 "Dwgs.User" user "User.Drawings")
		(19 "Cmts.User" user "User.Comments")
		(21 "Eco1.User" user "User.Eco1")
		(23 "Eco2.User" user "User.Eco2")
		(25 "Edge.Cuts" user "Board Geometry/Outline")
		(27 "Margin" user)
		(31 "F.CrtYd" user "Package Geometry/Place Bound Top")
		(29 "B.CrtYd" user "Package Geometry/Place Bound Bottom")
		(35 "F.Fab" user "Ref Des/Assembly Top")
		(33 "B.Fab" user "Ref Des/Assembly Bottom")
	)
	(footprint ""
		(layer "B.Cu")
		(at 97.587054 -79.60614 180)
		(property "Reference" "C8P13"
			(at 0 0 0)
			(layer "B.SilkS")
			(hide yes)
			(effects
				(font
					(size 1.27 1.27)
				)
				(justify mirror)
			)
		)
		(property "Value" ""
			(at 0 0 0)
			(layer "B.Fab")
			(effects
				(font
					(size 1.27 1.27)
				)
				(justify mirror)
			)
		)
		(duplicate_pad_numbers_are_jumpers no)
		(fp_poly
			(pts
				(xy 0.7239 -0.2159) (xy -0.7239 -0.2159) (xy -0.7239 1.9939) (xy 0.7239 1.9939)
			)
			(stroke
				(width 0)
				(type default)
			)
			(fill no)
			(layer "B.CrtYd")
		)
		(fp_line
			(start 0.7239 1.9939)
			(end -0.7239 1.9939)
			(stroke
				(width 0.1)
				(type default)
			)
			(layer "B.Fab")
		)
		(fp_line
			(start 0.7239 -0.2159)
			(end 0.7239 1.9939)
			(stroke
				(width 0.1)
				(type default)
			)
			(layer "B.Fab")
		)
		(fp_line
			(start -0.7239 1.9939)
			(end -0.7239 -0.2159)
			(stroke
				(width 0.1)
				(type default)
			)
			(layer "B.Fab")
		)
		(fp_line
			(start -0.7239 -0.2159)
			(end 0.7239 -0.2159)
			(stroke
				(width 0.1)
				(type default)
			)
			(layer "B.Fab")
		)
		(pad "1" smd rect
			(at 0 0)
			(size 1.27 1.016)
			(layers "B.Cu" "B.Mask" "B.Paste")
			(net "PVCCIN_CPU1")
		)
		(pad "2" smd rect
			(at 0 1.778)
			(size 1.27 1.016)
			(layers "B.Cu" "B.Mask" "B.Paste")
			(net "GND")
		)
		(zone
			(layer "B.Cu")
			(hatch none 0.5)
			(connect_pads
				(clearance 0)
			)
			(min_thickness 0.25)
			(keepout
				(tracks not_allowed)
				(vias allowed)
				(pads allowed)
				(copperpour not_allowed)
				(footprints allowed)
			)
			(placement
				(enabled no)
				(sheetname "")
			)
			(fill
				(thermal_gap 0.5)
				(thermal_bridge_width 0.5)
				(island_removal_mode 0)
			)
			(polygon
				(pts
					(xy 96.952054 -80.11414) (xy 98.222054 -80.11414) (xy 98.222054 -80.87614) (xy 96.952054 -80.87614)
				)
			)
		)
	)
	(footprint ""
		(layer "B.Cu")
		(at 104.521254 -77.82814)
		(property "Reference" "C8P15"
			(at 0 0 0)
			(layer "B.SilkS")
			(hide yes)
			(effects
				(font
					(size 1.27 1.27)
				)
				(justify mirror)
			)
		)
		(property "Value" ""
			(at 0 0 0)
			(layer "B.Fab")
			(effects
				(font
					(size 1.27 1.27)
				)
				(justify mirror)
			)
		)
		(duplicate_pad_numbers_are_jumpers no)
		(fp_poly
			(pts
				(xy 0.7239 -0.2159) (xy -0.7239 -0.2159) (xy -0.7239 1.9939) (xy 0.7239 1.9939)
			)
			(stroke
				(width 0)
				(type default)
			)
			(fill no)
			(layer "B.CrtYd")
		)
		(fp_line
			(start -0.7239 -0.2159)
			(end 0.7239 -0.2159)
			(stroke
				(width 0.1)
				(type default)
			)
			(layer "B.Fab")
		)
		(fp_line
			(start -0.7239 1.9939)
			(end -0.7239 -0.2159)
			(stroke
				(width 0.1)
				(type default)
			)
			(layer "B.Fab")
		)
		(fp_line
			(start 0.7239 -0.2159)
			(end 0.7239 1.9939)
			(stroke
				(width 0.1)
				(type default)
			)
			(layer "B.Fab")
		)
		(fp_line
			(start 0.7239 1.9939)
			(end -0.7239 1.9939)
			(stroke
				(width 0.1)
				(type default)
			)
			(layer "B.Fab")
		)
		(pad "1" smd rect
			(at 0 0 180)
			(size 1.27 1.016)
			(layers "B.Cu" "B.Mask" "B.Paste")
			(net "PVCCMCP_CPU1")
		)
		(pad "2" smd rect
			(at 0 1.778 180)
			(size 1.27 1.016)
			(layers "B.Cu" "B.Mask" "B.Paste")
			(net "GND")
		)
		(zone
			(layer "B.Cu")
			(hatch none 0.5)
			(connect_pads
				(clearance 0)
			)
			(min_thickness 0.25)
			(keepout
				(tracks not_allowed)
				(vias allowed)
				(pads allowed)
				(copperpour not_allowed)
				(footprints allowed)
			)
			(placement
				(enabled no)
				(sheetname "")
			)
			(fill
				(thermal_gap 0.5)
				(thermal_bridge_width 0.5)
				(island_removal_mode 0)
			)
			(polygon
				(pts
					(xy 105.156254 -77.32014) (xy 103.886254 -77.32014) (xy 103.886254 -76.55814) (xy 105.156254 -76.55814)
				)
			)
		)
	)
	(footprint ""
		(layer "B.Cu")
		(at 198.605648 -93.835982 90)
		(property "Reference" "C4C4"
			(at 0 0 90)
			(layer "B.SilkS")
			(hide yes)
			(effects
				(font
					(size 1.27 1.27)
				)
				(justify mirror)
			)
		)
		(property "Value" "*"
			(at -1.1811 -2.8194 90)
			(unlocked yes)
			(layer "B.Fab")
			(hide yes)
			(effects
				(font
					(size 1.27 1.016)
					(thickness 0.1524)
				)
				(justify mirror)
			)
		)
		(property "Device Type" "SC1U10V2KX-4-GP_SMD-BCG6-SC1U1A"
			(at -1.1811 -4.3434 90)
			(unlocked yes)
			(layer "B.Fab")
			(hide yes)
			(effects
				(font
					(size 1.27 1.016)
					(thickness 0.1524)
				)
				(justify mirror)
			)
		)
		(duplicate_pad_numbers_are_jumpers no)
		(fp_rect
			(start 0.4318 0.9525)
			(end -0.4318 -0.9525)
			(stroke
				(width 0)
				(type default)
			)
			(fill no)
			(layer "B.CrtYd")
		)
		(fp_rect
			(start 0.4318 0.9525)
			(end -0.4318 -0.9525)
			(stroke
				(width 0)
				(type default)
			)
			(fill no)
			(layer "B.Fab")
		)
		(pad "1" smd custom
			(at 0 -0.4445 270)
			(size 0.1524 0.1524)
			(layers "B.Cu" "B.Mask" "B.Paste")
			(net "P5V_STBY")
			(options
				(clearance outline)
				(anchor circle)
			)
			(primitives
				(gr_poly
					(pts
						(arc
							(start 0.3048 0.2032)
							(mid 0.275042 0.275042)
							(end 0.2032 0.3048)
						)
						(arc
							(start -0.2032 0.3048)
							(mid -0.275042 0.275042)
							(end -0.3048 0.2032)
						)
						(arc
							(start -0.3048 -0.2032)
							(mid -0.275042 -0.275042)
							(end -0.2032 -0.3048)
						)
						(arc
							(start 0.2032 -0.3048)
							(mid 0.275042 -0.275042)
							(end 0.3048 -0.2032)
						)
					)
					(width 0)
					(fill yes)
				)
			)
		)
		(pad "2" smd custom
			(at 0 0.4445 270)
			(size 0.1524 0.1524)
			(layers "B.Cu" "B.Mask" "B.Paste")
			(net "GND")
			(options
				(clearance outline)
				(anchor circle)
			)
			(primitives
				(gr_poly
					(pts
						(arc
							(start 0.3048 0.2032)
							(mid 0.275042 0.275042)
							(end 0.2032 0.3048)
						)
						(arc
							(start -0.2032 0.3048)
							(mid -0.275042 0.275042)
							(end -0.3048 0.2032)
						)
						(arc
							(start -0.3048 -0.2032)
							(mid -0.275042 -0.275042)
							(end -0.2032 -0.3048)
						)
						(arc
							(start 0.2032 -0.3048)
							(mid 0.275042 -0.275042)
							(end 0.3048 -0.2032)
						)
					)
					(width 0)
					(fill yes)
				)
			)
		)
	)
	(footprint ""
		(layer "B.Cu")
		(at 264.035286 -73.51014)
		(property "Reference" "C5P34"
			(at 0 0 0)
			(layer "B.SilkS")
			(hide yes)
			(effects
				(font
					(size 1.27 1.27)
				)
				(justify mirror)
			)
		)
		(property "Value" ""
			(at 0 0 0)
			(layer "B.Fab")
			(effects
				(font
					(size 1.27 1.27)
				)
				(justify mirror)
			)
		)
		(duplicate_pad_numbers_are_jumpers no)
		(fp_poly
			(pts
				(xy 0.7239 -0.2159) (xy -0.7239 -0.2159) (xy -0.7239 1.9939) (xy 0.7239 1.9939)
			)
			(stroke
				(width 0)
				(type default)
			)
			(fill no)
			(layer "B.CrtYd")
		)
		(fp_line
			(start -0.7239 -0.2159)
			(end 0.7239 -0.2159)
			(stroke
				(width 0.1)
				(type default)
			)
			(layer "B.Fab")
		)
		(fp_line
			(start -0.7239 1.9939)
			(end -0.7239 -0.2159)
			(stroke
				(width 0.1)
				(type default)
			)
			(layer "B.Fab")
		)
		(fp_line
			(start 0.7239 -0.2159)
			(end 0.7239 1.9939)
			(stroke
				(width 0.1)
				(type default)
			)
			(layer "B.Fab")
		)
		(fp_line
			(start 0.7239 1.9939)
			(end -0.7239 1.9939)
			(stroke
				(width 0.1)
				(type default)
			)
			(layer "B.Fab")
		)
		(pad "1" smd rect
			(at 0 0 180)
			(size 1.27 1.016)
			(layers "B.Cu" "B.Mask" "B.Paste")
			(net "PVCCIN_CPU0")
		)
		(pad "2" smd rect
			(at 0 1.778 180)
			(size 1.27 1.016)
			(layers "B.Cu" "B.Mask" "B.Paste")
			(net "GND")
		)
		(zone
			(layer "B.Cu")
			(hatch none 0.5)
			(connect_pads
				(clearance 0)
			)
			(min_thickness 0.25)
			(keepout
				(tracks not_allowed)
				(vias allowed)
				(pads allowed)
				(copperpour not_allowed)
				(footprints allowed)
			)
			(placement
				(enabled no)
				(sheetname "")
			)
			(fill
				(thermal_gap 0.5)
				(thermal_bridge_width 0.5)
				(island_removal_mode 0)
			)
			(polygon
				(pts
					(xy 264.670286 -73.00214) (xy 263.400286 -73.00214) (xy 263.400286 -72.24014) (xy 264.670286 -72.24014)
				)
			)
		)
	)
)
